(kicad_pcb
	(version 20241229)
	(generator "pcbnew")
	(generator_version "9.0")
	(general
		(thickness 1.61)
		(legacy_teardrops no)
	)
	(paper "A3")
	(title_block
		(title "RDIMM DDR5 Tester")
		(date "2026-05-21")
		(rev "2.2.0")
		(company "Antmicro")
		(comment 9 "footprints 590-594 of 796")
	)
	(layers
		(0 "F.Cu" signal)
		(4 "In1.Cu" power)
		(6 "In2.Cu" mixed)
		(8 "In3.Cu" power)
		(10 "In4.Cu" mixed)
		(12 "In5.Cu" power)
		(14 "In6.Cu" mixed)
		(16 "In7.Cu" power)
		(18 "In8.Cu" power)
		(20 "In9.Cu" mixed)
		(22 "In10.Cu" power)
		(2 "B.Cu" signal)
		(9 "F.Adhes" user "F.Adhesive")
		(11 "B.Adhes" user "B.Adhesive")
		(13 "F.Paste" user)
		(15 "B.Paste" user)
		(5 "F.SilkS" user "F.Silkscreen")
		(7 "B.SilkS" user "B.Silkscreen")
		(1 "F.Mask" user)
		(3 "B.Mask" user)
		(17 "Dwgs.User" user "User.Drawings")
		(19 "Cmts.User" user "User.Comments")
		(21 "Eco1.User" user "User.Eco1")
		(23 "Eco2.User" user "User.Eco2")
		(25 "Edge.Cuts" user)
		(27 "Margin" user)
		(31 "F.CrtYd" user "F.Courtyard")
		(29 "B.CrtYd" user "B.Courtyard")
		(35 "F.Fab" user)
		(33 "B.Fab" user)
	)
	(footprint "antmicro-footprints:R_0402_1005Metric_EIA"
		(layer "B.Cu")
		(at 179 145.505 -90)
		(descr "Resistor SMD 0402 (1005 Metric), square (rectangular) end terminal, IPC_7351 nominal, (Body size source: IPC-SM-782 page 76, https://www.pcb-3d.com/wordpress/wp-content/uploads/ipc-sm-782a_amendment_1_and_2.pdf)")
		(tags "resistor 0402")
		(property "Reference" "R35"
			(at -1.03 -1.475 90)
			(layer "B.SilkS")
			(effects
				(font
					(size 0.7 0.7)
					(thickness 0.15)
				)
				(justify left bottom mirror)
			)
		)
		(property "Value" "R_100R_0402"
			(at 0 -1.169 90)
			(layer "B.Fab")
			(effects
				(font
					(size 0.7 0.7)
					(thickness 0.15)
				)
				(justify left bottom mirror)
			)
		)
		(property "Datasheet" "https://www.bourns.com/docs/product-datasheets/cr.pdf"
			(at 0 0 270)
			(layer "F.Fab")
			(hide yes)
			(effects
				(font
					(size 1.27 1.27)
					(thickness 0.15)
				)
			)
		)
		(property "MPN" "CR0402-FX-1000GLF"
			(at 0 0 270)
			(unlocked yes)
			(layer "B.Fab")
			(hide yes)
			(effects
				(font
					(size 1 1)
					(thickness 0.15)
				)
				(justify mirror)
			)
		)
		(property "Manufacturer" "Bourns"
			(at 0 0 270)
			(unlocked yes)
			(layer "B.Fab")
			(hide yes)
			(effects
				(font
					(size 1 1)
					(thickness 0.15)
				)
				(justify mirror)
			)
		)
		(property "License" "Apache-2.0"
			(at 0 0 270)
			(unlocked yes)
			(layer "B.Fab")
			(hide yes)
			(effects
				(font
					(size 1 1)
					(thickness 0.15)
				)
				(justify mirror)
			)
		)
		(property "Author" "Antmicro"
			(at 0 0 270)
			(unlocked yes)
			(layer "B.Fab")
			(hide yes)
			(effects
				(font
					(size 1 1)
					(thickness 0.15)
				)
				(justify mirror)
			)
		)
		(property "Val" "100R"
			(at 0 0 270)
			(unlocked yes)
			(layer "B.Fab")
			(hide yes)
			(effects
				(font
					(size 1 1)
					(thickness 0.15)
				)
				(justify mirror)
			)
		)
		(property "Tolerance" "1%"
			(at 0 0 270)
			(unlocked yes)
			(layer "B.Fab")
			(hide yes)
			(effects
				(font
					(size 1 1)
					(thickness 0.15)
				)
				(justify mirror)
			)
		)
		(sheetname "/FPGA MGT Interface/")
		(sheetfile "fpga-mgt.kicad_sch")
		(attr smd)
		(fp_rect
			(start -0.95 0.45)
			(end 0.95 -0.45)
			(stroke
				(width 0.05)
				(type default)
			)
			(fill no)
			(layer "B.CrtYd")
		)
		(fp_line
			(start -0.5 0.25)
			(end 0.499 0.25)
			(stroke
				(width 0.15)
				(type solid)
			)
			(layer "B.Fab")
		)
		(fp_line
			(start 0.499 0.25)
			(end 0.499 -0.249)
			(stroke
				(width 0.15)
				(type solid)
			)
			(layer "B.Fab")
		)
		(fp_line
			(start -0.5 -0.249)
			(end -0.5 0.25)
			(stroke
				(width 0.15)
				(type solid)
			)
			(layer "B.Fab")
		)
		(fp_line
			(start 0.499 -0.249)
			(end -0.5 -0.249)
			(stroke
				(width 0.15)
				(type solid)
			)
			(layer "B.Fab")
		)
		(fp_text user "${REFERENCE}"
			(at -0.95 -3.169 90)
			(layer "B.Fab")
			(effects
				(font
					(size 0.7 0.7)
					(thickness 0.15)
				)
				(justify left bottom mirror)
			)
		)
		(fp_text user "License: Apache-2.0"
			(at -0.95 -4.369 90)
			(layer "B.Fab")
			(effects
				(font
					(size 0.7 0.7)
					(thickness 0.15)
				)
				(justify left bottom mirror)
			)
		)
		(fp_text user "Author: Antmicro"
			(at -0.95 -5.569 90)
			(layer "B.Fab")
			(effects
				(font
					(size 0.7 0.7)
					(thickness 0.15)
				)
				(justify left bottom mirror)
			)
		)
		(pad "1" smd roundrect
			(at -0.5 0 180)
			(size 0.6 0.6)
			(layers "B.Cu" "B.Mask" "B.Paste")
			(roundrect_rratio 0.25)
			(net 458 "HDMI_REC_CLK_N")
			(pintype "passive")
		)
		(pad "2" smd roundrect
			(at 0.499 0 270)
			(size 0.6 0.6)
			(layers "B.Cu" "B.Mask" "B.Paste")
			(roundrect_rratio 0.25)
			(net 403 "HDMI_REC_CLK_P")
			(pintype "passive")
		)
	)
	(footprint "antmicro-footprints:R_0402_1005Metric"
		(layer "B.Cu")
		(at 260.549499 170.849 90)
		(descr "Resistor SMD 0402")
		(tags "resistor SMD 0402")
		(property "Reference" "R164"
			(at 0.999 0.350501 90)
			(layer "B.SilkS")
			(effects
				(font
					(size 0.7 0.7)
					(thickness 0.15)
				)
				(justify right bottom mirror)
			)
		)
		(property "Value" "R_0R_0402"
			(at -1.011843 -1.772047 90)
			(layer "B.Fab")
			(effects
				(font
					(size 0.7 0.7)
					(thickness 0.15)
				)
				(justify right bottom mirror)
			)
		)
		(property "Datasheet" "https://industrial.panasonic.com/cdbs/www-data/pdf/RDA0000/AOA0000C301.pdf"
			(at 0 0 90)
			(layer "F.Fab")
			(hide yes)
			(effects
				(font
					(size 1.27 1.27)
					(thickness 0.15)
				)
			)
		)
		(property "Manufacturer" "Panasonic"
			(at 0 0 90)
			(unlocked yes)
			(layer "B.Fab")
			(hide yes)
			(effects
				(font
					(size 1 1)
					(thickness 0.15)
				)
				(justify mirror)
			)
		)
		(property "MPN" "ERJ2GE0R00X"
			(at 0 0 90)
			(unlocked yes)
			(layer "B.Fab")
			(hide yes)
			(effects
				(font
					(size 1 1)
					(thickness 0.15)
				)
				(justify mirror)
			)
		)
		(property "Val" "0R"
			(at 0 0 90)
			(unlocked yes)
			(layer "B.Fab")
			(hide yes)
			(effects
				(font
					(size 1 1)
					(thickness 0.15)
				)
				(justify mirror)
			)
		)
		(property "License" "Apache-2.0"
			(at 0 0 90)
			(unlocked yes)
			(layer "B.Fab")
			(hide yes)
			(effects
				(font
					(size 1 1)
					(thickness 0.15)
				)
				(justify mirror)
			)
		)
		(property "Author" "Antmicro"
			(at 0 0 90)
			(unlocked yes)
			(layer "B.Fab")
			(hide yes)
			(effects
				(font
					(size 1 1)
					(thickness 0.15)
				)
				(justify mirror)
			)
		)
		(property "Tolerance" "~"
			(at 0 0 90)
			(unlocked yes)
			(layer "B.Fab")
			(hide yes)
			(effects
				(font
					(size 1 1)
					(thickness 0.15)
				)
				(justify mirror)
			)
		)
		(property "Current" "1A"
			(at 0 0 90)
			(unlocked yes)
			(layer "B.Fab")
			(hide yes)
			(effects
				(font
					(size 1 1)
					(thickness 0.15)
				)
				(justify mirror)
			)
		)
		(sheetname "/Supply/DC-DC AUX, MGT/")
		(sheetfile "dc-dc-aux-mgt.kicad_sch")
		(attr smd exclude_from_bom dnp)
		(fp_rect
			(start -0.925 0.47)
			(end 0.925 -0.47)
			(stroke
				(width 0.05)
				(type default)
			)
			(fill no)
			(layer "B.CrtYd")
		)
		(fp_rect
			(start -0.5 0.25)
			(end 0.5 -0.25)
			(stroke
				(width 0.15)
				(type solid)
			)
			(fill no)
			(layer "B.Fab")
		)
		(fp_text user "License: Apache-2.0"
			(at -0.95 -5.169 270)
			(layer "B.Fab")
			(effects
				(font
					(size 0.7 0.7)
					(thickness 0.15)
				)
				(justify left bottom mirror)
			)
		)
		(fp_text user "${REFERENCE}"
			(at -0.95 -3.168 270)
			(layer "B.Fab")
			(effects
				(font
					(size 0.7 0.7)
					(thickness 0.15)
				)
				(justify left bottom mirror)
			)
		)
		(fp_text user "Author: Antmicro"
			(at -0.95 -4.169 270)
			(layer "B.Fab")
			(effects
				(font
					(size 0.7 0.7)
					(thickness 0.15)
				)
				(justify left bottom mirror)
			)
		)
		(pad "1" smd roundrect
			(at -0.48 0 90)
			(size 0.59 0.64)
			(layers "B.Cu" "B.Mask" "B.Paste")
			(roundrect_rratio 0.25)
			(net 1 "GND")
			(pintype "passive")
		)
		(pad "2" smd roundrect
			(at 0.48 0 90)
			(size 0.59 0.64)
			(layers "B.Cu" "B.Mask" "B.Paste")
			(roundrect_rratio 0.25)
			(net 716 "/Supply/DC-DC AUX, MGT/FB3")
			(pintype "passive")
		)
	)
	(footprint "antmicro-footprints:C_0402_1005Metric_EIA"
		(layer "B.Cu")
		(at 193 150.5 90)
		(descr "Capacitor SMD 0402 (1005 Metric), square (rectangular) end terminal, IPC_7351 nominal, (Body size source: IPC-SM-782 page 76, https://www.pcb-3d.com/wordpress/wp-content/uploads/ipc-sm-782a_amendment_1_and_2.pdf)")
		(tags "capacitor 0402")
		(property "Reference" "C59"
			(at 9.8 -30.675 90)
			(layer "B.SilkS")
			(effects
				(font
					(size 0.7 0.7)
					(thickness 0.15)
				)
				(justify right bottom mirror)
			)
		)
		(property "Value" "C_1u_25V_0402"
			(at 0 -1.169 90)
			(layer "B.Fab")
			(effects
				(font
					(size 0.7 0.7)
					(thickness 0.15)
				)
				(justify right bottom mirror)
			)
		)
		(property "Datasheet" "https://www.murata.com/products/productdetail?partno=GRM155R61E105KE11%23"
			(at 0 0 90)
			(layer "F.Fab")
			(hide yes)
			(effects
				(font
					(size 1.27 1.27)
					(thickness 0.15)
				)
			)
		)
		(property "MPN" "GRM155R61E105KE11J"
			(at 0 0 90)
			(unlocked yes)
			(layer "B.Fab")
			(hide yes)
			(effects
				(font
					(size 1 1)
					(thickness 0.15)
				)
				(justify mirror)
			)
		)
		(property "Manufacturer" "Murata"
			(at 0 0 90)
			(unlocked yes)
			(layer "B.Fab")
			(hide yes)
			(effects
				(font
					(size 1 1)
					(thickness 0.15)
				)
				(justify mirror)
			)
		)
		(property "License" "Apache-2.0"
			(at 0 0 90)
			(unlocked yes)
			(layer "B.Fab")
			(hide yes)
			(effects
				(font
					(size 1 1)
					(thickness 0.15)
				)
				(justify mirror)
			)
		)
		(property "Author" "Antmicro"
			(at 0 0 90)
			(unlocked yes)
			(layer "B.Fab")
			(hide yes)
			(effects
				(font
					(size 1 1)
					(thickness 0.15)
				)
				(justify mirror)
			)
		)
		(property "Val" "1u"
			(at 0 0 90)
			(unlocked yes)
			(layer "B.Fab")
			(hide yes)
			(effects
				(font
					(size 1 1)
					(thickness 0.15)
				)
				(justify mirror)
			)
		)
		(property "Voltage" "25V"
			(at 0 0 90)
			(unlocked yes)
			(layer "B.Fab")
			(hide yes)
			(effects
				(font
					(size 1 1)
					(thickness 0.15)
				)
				(justify mirror)
			)
		)
		(property "Dielectric" "X5R"
			(at 0 0 90)
			(unlocked yes)
			(layer "B.Fab")
			(hide yes)
			(effects
				(font
					(size 1 1)
					(thickness 0.15)
				)
				(justify mirror)
			)
		)
		(sheetname "/FPGA power/")
		(sheetfile "fpga-power.kicad_sch")
		(attr smd)
		(fp_rect
			(start -0.95 0.45)
			(end 0.95 -0.45)
			(stroke
				(width 0.05)
				(type default)
			)
			(fill no)
			(layer "B.CrtYd")
		)
		(fp_line
			(start 0.498 -0.248)
			(end -0.5 -0.248)
			(stroke
				(width 0.15)
				(type solid)
			)
			(layer "B.Fab")
		)
		(fp_line
			(start -0.5 -0.248)
			(end -0.5 0.25)
			(stroke
				(width 0.15)
				(type solid)
			)
			(layer "B.Fab")
		)
		(fp_line
			(start 0.498 0.25)
			(end 0.498 -0.248)
			(stroke
				(width 0.15)
				(type solid)
			)
			(layer "B.Fab")
		)
		(fp_line
			(start -0.5 0.25)
			(end 0.498 0.25)
			(stroke
				(width 0.15)
				(type solid)
			)
			(layer "B.Fab")
		)
		(fp_text user "Author: Antmicro"
			(at -0.9656 -5.569 270)
			(layer "B.Fab")
			(effects
				(font
					(size 0.7 0.7)
					(thickness 0.15)
				)
				(justify left bottom mirror)
			)
		)
		(fp_text user "${REFERENCE}"
			(at -0.9656 -3.169 270)
			(layer "B.Fab")
			(effects
				(font
					(size 0.7 0.7)
					(thickness 0.15)
				)
				(justify left bottom mirror)
			)
		)
		(fp_text user "License: Apache-2.0"
			(at -0.9656 -4.369 270)
			(layer "B.Fab")
			(effects
				(font
					(size 0.7 0.7)
					(thickness 0.15)
				)
				(justify left bottom mirror)
			)
		)
		(pad "1" smd roundrect
			(at -0.5 0)
			(size 0.6 0.6)
			(layers "B.Cu" "B.Mask" "B.Paste")
			(roundrect_rratio 0.25)
			(net 1 "GND")
			(pintype "passive")
		)
		(pad "2" smd roundrect
			(at 0.498 0 90)
			(size 0.6 0.6)
			(layers "B.Cu" "B.Mask" "B.Paste")
			(roundrect_rratio 0.25)
			(net 553 "+0V85")
			(pintype "passive")
		)
	)
	(footprint "antmicro-footprints:C_0805_2012Metric"
		(layer "B.Cu")
		(at 219.315001 187.679999)
		(descr "Capacitor SMD 0805")
		(tags "capacitor SMD 0805")
		(property "Reference" "C177"
			(at 2.134999 1.120001 0)
			(layer "B.SilkS")
			(effects
				(font
					(size 0.7 0.7)
					(thickness 0.15)
				)
				(justify right bottom mirror)
			)
		)
		(property "Value" "C_22u_25V_0805"
			(at -2.055717 -1.963152 0)
			(layer "B.Fab")
			(effects
				(font
					(size 0.7 0.7)
					(thickness 0.15)
				)
				(justify right bottom mirror)
			)
		)
		(property "Datasheet" "https://product.samsungsem.com/mlcc/CL21A226MAYNNN.do"
			(at 0 0 0)
			(layer "F.Fab")
			(hide yes)
			(effects
				(font
					(size 1.27 1.27)
					(thickness 0.15)
				)
			)
		)
		(property "MPN" "CL21A226MAYNNNE"
			(at 0 0 0)
			(unlocked yes)
			(layer "B.Fab")
			(hide yes)
			(effects
				(font
					(size 1 1)
					(thickness 0.15)
				)
				(justify mirror)
			)
		)
		(property "Manufacturer" "Samsung Electro-Mechanics"
			(at 0 0 0)
			(unlocked yes)
			(layer "B.Fab")
			(hide yes)
			(effects
				(font
					(size 1 1)
					(thickness 0.15)
				)
				(justify mirror)
			)
		)
		(property "License" "Apache-2.0"
			(at 0 0 0)
			(unlocked yes)
			(layer "B.Fab")
			(hide yes)
			(effects
				(font
					(size 1 1)
					(thickness 0.15)
				)
				(justify mirror)
			)
		)
		(property "Author" "Antmicro"
			(at 0 0 0)
			(unlocked yes)
			(layer "B.Fab")
			(hide yes)
			(effects
				(font
					(size 1 1)
					(thickness 0.15)
				)
				(justify mirror)
			)
		)
		(property "Val" "22u"
			(at 0 0 0)
			(unlocked yes)
			(layer "B.Fab")
			(hide yes)
			(effects
				(font
					(size 1 1)
					(thickness 0.15)
				)
				(justify mirror)
			)
		)
		(property "Voltage" "25V"
			(at 0 0 0)
			(unlocked yes)
			(layer "B.Fab")
			(hide yes)
			(effects
				(font
					(size 1 1)
					(thickness 0.15)
				)
				(justify mirror)
			)
		)
		(property "Dielectric" "X5R"
			(at 0 0 0)
			(unlocked yes)
			(layer "B.Fab")
			(hide yes)
			(effects
				(font
					(size 1 1)
					(thickness 0.15)
				)
				(justify mirror)
			)
		)
		(property "Public" "False"
			(at 0 0 0)
			(unlocked yes)
			(layer "B.Fab")
			(hide yes)
			(effects
				(font
					(size 1 1)
					(thickness 0.15)
				)
				(justify mirror)
			)
		)
		(sheetname "/Supply/DC-DC VCCINT/")
		(sheetfile "dc-dc-vccint.kicad_sch")
		(attr smd)
		(fp_line
			(start -0.3 -0.7)
			(end 0.3 -0.7)
			(stroke
				(width 0.15)
				(type solid)
			)
			(layer "B.SilkS")
		)
		(fp_line
			(start -0.3 0.7)
			(end 0.3 0.7)
			(stroke
				(width 0.15)
				(type solid)
			)
			(layer "B.SilkS")
		)
		(fp_rect
			(start 1.95 0.9)
			(end -1.95 -0.9)
			(stroke
				(width 0.05)
				(type default)
			)
			(fill no)
			(layer "B.CrtYd")
		)
		(fp_rect
			(start -0.95 0.675)
			(end 0.95 -0.675)
			(stroke
				(width 0.15)
				(type solid)
			)
			(fill no)
			(layer "B.Fab")
		)
		(fp_text user "License: Apache-2.0"
			(at -1.9 -4.947 180)
			(layer "B.Fab")
			(effects
				(font
					(size 0.7 0.7)
					(thickness 0.15)
				)
				(justify left bottom mirror)
			)
		)
		(fp_text user "${REFERENCE}"
			(at -1.9 -3.947 180)
			(layer "B.Fab")
			(effects
				(font
					(size 0.7 0.7)
					(thickness 0.15)
				)
				(justify left bottom mirror)
			)
		)
		(fp_text user "Author: Antmicro"
			(at -1.9 -5.947 180)
			(layer "B.Fab")
			(effects
				(font
					(size 0.7 0.7)
					(thickness 0.15)
				)
				(justify left bottom mirror)
			)
		)
		(pad "1" smd roundrect
			(at -1.1 0)
			(size 1.2 1.3)
			(layers "B.Cu" "B.Mask" "B.Paste")
			(roundrect_rratio 0.25)
			(net 1 "GND")
			(pintype "passive")
		)
		(pad "2" smd roundrect
			(at 1.1 0)
			(size 1.2 1.3)
			(layers "B.Cu" "B.Mask" "B.Paste")
			(roundrect_rratio 0.25)
			(net 35 "VDC")
			(pintype "passive")
		)
	)
	(footprint "antmicro-footprints:C_0402_1005Metric_EIA"
		(layer "B.Cu")
		(at 190 148.498 90)
		(descr "Capacitor SMD 0402 (1005 Metric), square (rectangular) end terminal, IPC_7351 nominal, (Body size source: IPC-SM-782 page 76, https://www.pcb-3d.com/wordpress/wp-content/uploads/ipc-sm-782a_amendment_1_and_2.pdf)")
		(tags "capacitor 0402")
		(property "Reference" "C56"
			(at 9.823 -30.675 90)
			(layer "B.SilkS")
			(effects
				(font
					(size 0.7 0.7)
					(thickness 0.15)
				)
				(justify right bottom mirror)
			)
		)
		(property "Value" "C_1u_25V_0402"
			(at 0 -1.169 90)
			(layer "B.Fab")
			(effects
				(font
					(size 0.7 0.7)
					(thickness 0.15)
				)
				(justify right bottom mirror)
			)
		)
		(property "Datasheet" "https://www.murata.com/products/productdetail?partno=GRM155R61E105KE11%23"
			(at 0 0 90)
			(layer "F.Fab")
			(hide yes)
			(effects
				(font
					(size 1.27 1.27)
					(thickness 0.15)
				)
			)
		)
		(property "MPN" "GRM155R61E105KE11J"
			(at 0 0 90)
			(unlocked yes)
			(layer "B.Fab")
			(hide yes)
			(effects
				(font
					(size 1 1)
					(thickness 0.15)
				)
				(justify mirror)
			)
		)
		(property "Manufacturer" "Murata"
			(at 0 0 90)
			(unlocked yes)
			(layer "B.Fab")
			(hide yes)
			(effects
				(font
					(size 1 1)
					(thickness 0.15)
				)
				(justify mirror)
			)
		)
		(property "License" "Apache-2.0"
			(at 0 0 90)
			(unlocked yes)
			(layer "B.Fab")
			(hide yes)
			(effects
				(font
					(size 1 1)
					(thickness 0.15)
				)
				(justify mirror)
			)
		)
		(property "Author" "Antmicro"
			(at 0 0 90)
			(unlocked yes)
			(layer "B.Fab")
			(hide yes)
			(effects
				(font
					(size 1 1)
					(thickness 0.15)
				)
				(justify mirror)
			)
		)
		(property "Val" "1u"
			(at 0 0 90)
			(unlocked yes)
			(layer "B.Fab")
			(hide yes)
			(effects
				(font
					(size 1 1)
					(thickness 0.15)
				)
				(justify mirror)
			)
		)
		(property "Voltage" "25V"
			(at 0 0 90)
			(unlocked yes)
			(layer "B.Fab")
			(hide yes)
			(effects
				(font
					(size 1 1)
					(thickness 0.15)
				)
				(justify mirror)
			)
		)
		(property "Dielectric" "X5R"
			(at 0 0 90)
			(unlocked yes)
			(layer "B.Fab")
			(hide yes)
			(effects
				(font
					(size 1 1)
					(thickness 0.15)
				)
				(justify mirror)
			)
		)
		(sheetname "/FPGA power/")
		(sheetfile "fpga-power.kicad_sch")
		(attr smd)
		(fp_rect
			(start -0.95 0.45)
			(end 0.95 -0.45)
			(stroke
				(width 0.05)
				(type default)
			)
			(fill no)
			(layer "B.CrtYd")
		)
		(fp_line
			(start 0.498 -0.248)
			(end -0.5 -0.248)
			(stroke
				(width 0.15)
				(type solid)
			)
			(layer "B.Fab")
		)
		(fp_line
			(start -0.5 -0.248)
			(end -0.5 0.25)
			(stroke
				(width 0.15)
				(type solid)
			)
			(layer "B.Fab")
		)
		(fp_line
			(start 0.498 0.25)
			(end 0.498 -0.248)
			(stroke
				(width 0.15)
				(type solid)
			)
			(layer "B.Fab")
		)
		(fp_line
			(start -0.5 0.25)
			(end 0.498 0.25)
			(stroke
				(width 0.15)
				(type solid)
			)
			(layer "B.Fab")
		)
		(fp_text user "Author: Antmicro"
			(at -0.9656 -5.569 270)
			(layer "B.Fab")
			(effects
				(font
					(size 0.7 0.7)
					(thickness 0.15)
				)
				(justify left bottom mirror)
			)
		)
		(fp_text user "${REFERENCE}"
			(at -0.9656 -3.169 270)
			(layer "B.Fab")
			(effects
				(font
					(size 0.7 0.7)
					(thickness 0.15)
				)
				(justify left bottom mirror)
			)
		)
		(fp_text user "License: Apache-2.0"
			(at -0.9656 -4.369 270)
			(layer "B.Fab")
			(effects
				(font
					(size 0.7 0.7)
					(thickness 0.15)
				)
				(justify left bottom mirror)
			)
		)
		(pad "1" smd roundrect
			(at -0.5 0)
			(size 0.6 0.6)
			(layers "B.Cu" "B.Mask" "B.Paste")
			(roundrect_rratio 0.25)
			(net 1 "GND")
			(pintype "passive")
		)
		(pad "2" smd roundrect
			(at 0.498 0 90)
			(size 0.6 0.6)
			(layers "B.Cu" "B.Mask" "B.Paste")
			(roundrect_rratio 0.25)
			(net 553 "+0V85")
			(pintype "passive")
		)
	)
)
